#ISCELL
  pure_quanta quanta_title_block_c *
  *
#ISCELL
  pure_quanta_power cad_note *
  *
#CELL
  pure_quanta genoa_sp5 *
  page43_i167
#ISCELL
  mstr_standard offpage *
  page43_i168
#ISCELL
  mstr_standard offpage *
  page43_i169
#ISCELL
  mstr_standard tap *
  page43_i170
#ISCELL
  mstr_standard tap *
  page43_i171
#ISCELL
  mstr_standard tap *
  page43_i172
#ISCELL
  mstr_standard tap *
  page43_i173
#ISCELL
  mstr_standard tap *
  page43_i174
#ISCELL
  mstr_standard tap *
  page43_i175
#ISCELL
  mstr_standard tap *
  page43_i176
#ISCELL
  mstr_standard tap *
  page43_i177
#ISCELL
  mstr_standard tap *
  page43_i178
#ISCELL
  mstr_standard tap *
  page43_i179
#ISCELL
  mstr_standard tap *
  page43_i180
#ISCELL
  mstr_standard tap *
  page43_i181
#ISCELL
  mstr_standard tap *
  page43_i182
#ISCELL
  mstr_standard tap *
  page43_i183
#ISCELL
  mstr_standard tap *
  page43_i184
#ISCELL
  mstr_standard tap *
  page43_i185
#ISCELL
  mstr_standard tap *
  page43_i186
#ISCELL
  mstr_standard tap *
  page43_i187
#ISCELL
  mstr_standard tap *
  page43_i188
#ISCELL
  mstr_standard tap *
  page43_i189
#ISCELL
  mstr_standard tap *
  page43_i190
#ISCELL
  mstr_standard tap *
  page43_i191
#ISCELL
  mstr_standard tap *
  page43_i192
#ISCELL
  mstr_standard tap *
  page43_i193
#ISCELL
  mstr_standard tap *
  page43_i194
#ISCELL
  mstr_standard tap *
  page43_i195
#ISCELL
  mstr_standard tap *
  page43_i196
#ISCELL
  mstr_standard tap *
  page43_i197
#ISCELL
  mstr_standard tap *
  page43_i198
#ISCELL
  mstr_standard tap *
  page43_i199
#ISCELL
  mstr_standard tap *
  page43_i200
#ISCELL
  mstr_standard tap *
  page43_i201
#ISCELL
  mstr_standard tap *
  page43_i202
#ISCELL
  mstr_standard tap *
  page43_i203
#ISCELL
  mstr_standard tap *
  page43_i204
#ISCELL
  mstr_standard tap *
  page43_i205
#ISCELL
  mstr_standard offpage *
  page43_i206
#ISCELL
  mstr_standard tap *
  page43_i207
#ISCELL
  mstr_standard tap *
  page43_i208
#ISCELL
  mstr_standard tap *
  page43_i209
#ISCELL
  mstr_standard tap *
  page43_i210
#ISCELL
  mstr_standard tap *
  page43_i211
#ISCELL
  mstr_standard tap *
  page43_i212
#ISCELL
  mstr_standard tap *
  page43_i213
#ISCELL
  mstr_standard tap *
  page43_i214
#ISCELL
  mstr_standard tap *
  page43_i215
#ISCELL
  mstr_standard tap *
  page43_i216
#ISCELL
  mstr_standard tap *
  page43_i217
#ISCELL
  mstr_standard tap *
  page43_i218
#ISCELL
  mstr_standard tap *
  page43_i219
#ISCELL
  mstr_standard tap *
  page43_i220
#ISCELL
  mstr_standard tap *
  page43_i221
#ISCELL
  mstr_standard tap *
  page43_i222
#ISCELL
  mstr_standard tap *
  page43_i223
#ISCELL
  mstr_standard tap *
  page43_i224
#ISCELL
  mstr_standard tap *
  page43_i225
#ISCELL
  mstr_standard tap *
  page43_i226
#ISCELL
  mstr_standard tap *
  page43_i227
#ISCELL
  mstr_standard tap *
  page43_i228
#ISCELL
  mstr_standard tap *
  page43_i229
#ISCELL
  mstr_standard tap *
  page43_i230
#ISCELL
  mstr_standard tap *
  page43_i231
#ISCELL
  mstr_standard tap *
  page43_i232
#ISCELL
  mstr_standard tap *
  page43_i233
#ISCELL
  mstr_standard tap *
  page43_i234
#ISCELL
  mstr_standard tap *
  page43_i235
#ISCELL
  mstr_standard tap *
  page43_i236
#ISCELL
  mstr_standard tap *
  page43_i237
#ISCELL
  mstr_standard tap *
  page43_i238
#ISCELL
  mstr_standard tap *
  page43_i239
#ISCELL
  mstr_standard tap *
  page43_i240
#ISCELL
  mstr_standard tap *
  page43_i241
#ISCELL
  mstr_standard tap *
  page43_i242
#ISCELL
  mstr_standard offpage *
  page43_i243
#ISCELL
  mstr_standard tap *
  page43_i244
#ISCELL
  mstr_standard tap *
  page43_i245
#ISCELL
  mstr_standard tap *
  page43_i246
#ISCELL
  mstr_standard tap *
  page43_i247
#ISCELL
  mstr_standard tap *
  page43_i248
#ISCELL
  mstr_standard tap *
  page43_i249
#ISCELL
  mstr_standard tap *
  page43_i250
#ISCELL
  mstr_standard tap *
  page43_i251
#ISCELL
  mstr_standard tap *
  page43_i252
#ISCELL
  mstr_standard tap *
  page43_i253
#ISCELL
  mstr_standard tap *
  page43_i254
#ISCELL
  mstr_standard tap *
  page43_i255
#ISCELL
  mstr_standard tap *
  page43_i256
#ISCELL
  mstr_standard tap *
  page43_i257
#ISCELL
  mstr_standard tap *
  page43_i258
#ISCELL
  mstr_standard tap *
  page43_i259
#ISCELL
  mstr_standard tap *
  page43_i260
#ISCELL
  mstr_standard tap *
  page43_i261
#ISCELL
  mstr_standard tap *
  page43_i262
#ISCELL
  mstr_standard tap *
  page43_i263
#ISCELL
  mstr_standard tap *
  page43_i264
#ISCELL
  mstr_standard tap *
  page43_i265
#ISCELL
  mstr_standard tap *
  page43_i266
#ISCELL
  mstr_standard tap *
  page43_i267
#ISCELL
  mstr_standard tap *
  page43_i268
#ISCELL
  mstr_standard tap *
  page43_i269
#ISCELL
  mstr_standard tap *
  page43_i270
#ISCELL
  mstr_standard tap *
  page43_i271
#ISCELL
  mstr_standard tap *
  page43_i272
#ISCELL
  mstr_standard tap *
  page43_i273
#ISCELL
  mstr_standard tap *
  page43_i274
#ISCELL
  mstr_standard tap *
  page43_i275
#ISCELL
  mstr_standard tap *
  page43_i276
#ISCELL
  mstr_standard tap *
  page43_i277
#ISCELL
  mstr_standard tap *
  page43_i278
#ISCELL
  mstr_standard tap *
  page43_i279
#ISCELL
  mstr_standard tap *
  page43_i280
#ISCELL
  mstr_standard tap *
  page43_i281
#ISCELL
  mstr_standard tap *
  page43_i282
#ISCELL
  mstr_standard tap *
  page43_i283
#ISCELL
  mstr_standard tap *
  page43_i284
#ISCELL
  mstr_standard tap *
  page43_i285
#ISCELL
  mstr_standard tap *
  page43_i286
#ISCELL
  mstr_standard tap *
  page43_i287
#ISCELL
  mstr_standard tap *
  page43_i288
#ISCELL
  mstr_standard tap *
  page43_i289
#ISCELL
  mstr_standard tap *
  page43_i290
#ISCELL
  standard offpage *
  page43_i291
#ISCELL
  standard offpage *
  page43_i292
#ISCELL
  standard offpage *
  page43_i293
#ISCELL
  standard offpage *
  page43_i294
#ISCELL
  mstr_standard tap *
  page43_i295
#ISCELL
  mstr_standard tap *
  page43_i296
#ISCELL
  mstr_standard tap *
  page43_i297
#ISCELL
  mstr_standard tap *
  page43_i298
#ISCELL
  mstr_standard tap *
  page43_i299
#ISCELL
  mstr_standard tap *
  page43_i300
#ISCELL
  mstr_standard tap *
  page43_i301
#ISCELL
  mstr_standard tap *
  page43_i302
#ISCELL
  mstr_standard tap *
  page43_i303
#ISCELL
  mstr_standard tap *
  page43_i304
#ISCELL
  mstr_standard tap *
  page43_i305
#ISCELL
  mstr_standard tap *
  page43_i306
#ISCELL
  mstr_standard tap *
  page43_i307
#ISCELL
  mstr_standard tap *
  page43_i308
#ISCELL
  mstr_standard tap *
  page43_i309
#ISCELL
  standard offpage *
  page43_i310
#ISCELL
  standard offpage *
  page43_i311
#ISCELL
  standard offpage *
  page43_i312
#ISCELL
  standard offpage *
  page43_i313
#ISCELL
  standard offpage *
  page43_i314
#ISCELL
  standard offpage *
  page43_i315
#ISCELL
  mstr_standard offpage *
  page43_i316
#ISCELL
  standard offpage *
  page43_i317
#ISCELL
  standard offpage *
  page43_i318
#ISCELL
  standard offpage *
  page43_i319
#ISCELL
  standard offpage *
  page43_i320
#ISCELL
  standard offpage *
  page43_i321
#CELL
  pure_quanta q_res *
  page43_i322
#ISCELL
  standard offpage *
  page43_i323
#ISCELL
  mstr_standard offpage *
  page43_i324
